(kicad_pcb
	(version 20260206)
	(generator "pcbnew")
	(generator_version "10.0")
	(general
		(thickness 1.6)
		(legacy_teardrops no)
	)
	(paper "A4")
	(title_block
		(title "Bryce Canyon_IOM_M2_16342-2_OCP.brd")
		(comment 1 "Bryce Canyon / footprints 170-176 of 1146")
	)
	(layers
		(0 "F.Cu" signal "TOP")
		(4 "In1.Cu" signal "L2GND")
		(6 "In2.Cu" signal "L3")
		(8 "In3.Cu" signal "L4VCC")
		(10 "In4.Cu" signal "L5VCC")
		(12 "In5.Cu" signal "L6")
		(14 "In6.Cu" signal "L7GND")
		(2 "B.Cu" signal "BOTTOM")
		(9 "F.Adhes" user "F.Adhesive")
		(11 "B.Adhes" user "B.Adhesive")
		(13 "F.Paste" user "Package Geometry/Pastemask Top")
		(15 "B.Paste" user "Package Geometry/Pastemask Bottom")
		(5 "F.SilkS" user "Ref Des/Silkscreen Top")
		(7 "B.SilkS" user "Ref Des/Silkscreen Bottom")
		(1 "F.Mask" user "Board Geometry/Soldermask Top")
		(3 "B.Mask" user "Board Geometry/Soldermask Bottom")
		(17 "Dwgs.User" user "User.Drawings")
		(19 "Cmts.User" user "User.Comments")
		(21 "Eco1.User" user "User.Eco1")
		(23 "Eco2.User" user "User.Eco2")
		(25 "Edge.Cuts" user "Board Geometry/Outline")
		(27 "Margin" user)
		(31 "F.CrtYd" user "Package Geometry/Place Bound Top")
		(29 "B.CrtYd" user "Package Geometry/Place Bound Bottom")
		(35 "F.Fab" user "Ref Des/Assembly Top")
		(33 "B.Fab" user "Ref Des/Assembly Bottom")
	)
	(footprint ""
		(layer "F.Cu")
		(at 92.6084 -125.3998 180)
		(property "Reference" "C522"
			(at 0 0 180)
			(layer "F.SilkS")
			(hide yes)
			(effects
				(font
					(size 1.27 1.27)
				)
			)
		)
		(property "Value" "SCD1U25V2KX-2-GP"
			(at 1.1811 -2.7051 180)
			(unlocked yes)
			(layer "F.Fab")
			(hide yes)
			(effects
				(font
					(size 1.016 1.016)
					(thickness 0.1524)
				)
			)
		)
		(property "Device Type" "C402H22"
			(at 1.1811 -4.2291 180)
			(unlocked yes)
			(layer "F.Fab")
			(hide yes)
			(effects
				(font
					(size 1.016 1.016)
					(thickness 0.1524)
				)
			)
		)
		(duplicate_pad_numbers_are_jumpers no)
		(fp_rect
			(start -0.4318 0.9525)
			(end 0.4318 -0.9525)
			(stroke
				(width 0)
				(type default)
			)
			(fill no)
			(layer "F.CrtYd")
		)
		(fp_rect
			(start -0.4318 0.9525)
			(end 0.4318 -0.9525)
			(stroke
				(width 0)
				(type default)
			)
			(fill no)
			(layer "F.Fab")
		)
		(pad "1" smd custom
			(at 0 -0.4445 180)
			(size 0.1524 0.1524)
			(layers "F.Cu" "F.Mask" "F.Paste")
			(net "P3V3_STBY")
			(options
				(clearance outline)
				(anchor circle)
			)
			(primitives
				(gr_poly
					(pts
						(arc
							(start 0.3048 -0.2032)
							(mid 0.275042 -0.275042)
							(end 0.2032 -0.3048)
						)
						(arc
							(start -0.2032 -0.3048)
							(mid -0.275042 -0.275042)
							(end -0.3048 -0.2032)
						)
						(arc
							(start -0.3048 0.2032)
							(mid -0.275042 0.275042)
							(end -0.2032 0.3048)
						)
						(arc
							(start 0.2032 0.3048)
							(mid 0.275042 0.275042)
							(end 0.3048 0.2032)
						)
					)
					(width 0)
					(fill yes)
				)
			)
		)
		(pad "2" smd custom
			(at 0 0.4445 180)
			(size 0.1524 0.1524)
			(layers "F.Cu" "F.Mask" "F.Paste")
			(net "GND")
			(options
				(clearance outline)
				(anchor circle)
			)
			(primitives
				(gr_poly
					(pts
						(arc
							(start 0.3048 -0.2032)
							(mid 0.275042 -0.275042)
							(end 0.2032 -0.3048)
						)
						(arc
							(start -0.2032 -0.3048)
							(mid -0.275042 -0.275042)
							(end -0.3048 -0.2032)
						)
						(arc
							(start -0.3048 0.2032)
							(mid -0.275042 0.275042)
							(end -0.2032 0.3048)
						)
						(arc
							(start 0.2032 0.3048)
							(mid 0.275042 0.275042)
							(end 0.3048 0.2032)
						)
					)
					(width 0)
					(fill yes)
				)
			)
		)
	)
	(footprint ""
		(layer "F.Cu")
		(at 85.45957 -144.252188 -90)
		(property "Reference" "R131"
			(at 0 0 270)
			(layer "F.SilkS")
			(hide yes)
			(effects
				(font
					(size 1.27 1.27)
				)
			)
		)
		(property "Value" "0R2J-2-GP"
			(at 0.064008 -3.993896 270)
			(unlocked yes)
			(layer "F.Fab")
			(hide yes)
			(effects
				(font
					(size 1.016 1.016)
					(thickness 0.1524)
				)
			)
		)
		(property "Device Type" "R402H16"
			(at 0.064008 -5.517896 270)
			(unlocked yes)
			(layer "F.Fab")
			(hide yes)
			(effects
				(font
					(size 1.016 1.016)
					(thickness 0.1524)
				)
			)
		)
		(duplicate_pad_numbers_are_jumpers no)
		(fp_line
			(start -0.508 -0.9398)
			(end -0.508 0.9398)
			(stroke
				(width 0.1524)
				(type default)
			)
			(layer "F.SilkS")
		)
		(fp_line
			(start 0.508 -0.9398)
			(end -0.508 -0.9398)
			(stroke
				(width 0.1524)
				(type default)
			)
			(layer "F.SilkS")
		)
		(fp_rect
			(start -0.508 0.9398)
			(end 0.508 -0.9398)
			(stroke
				(width 0)
				(type default)
			)
			(fill no)
			(layer "F.CrtYd")
		)
		(fp_rect
			(start -0.508 0.9398)
			(end 0.508 -0.9398)
			(stroke
				(width 0)
				(type default)
			)
			(fill no)
			(layer "F.Fab")
		)
		(pad "1" smd custom
			(at 0 -0.4445 270)
			(size 0.1397 0.1397)
			(layers "F.Cu" "F.Mask" "F.Paste")
			(net "I2C_SCC_SCL")
			(options
				(clearance outline)
				(anchor circle)
			)
			(primitives
				(gr_poly
					(pts
						(arc
							(start -0.1778 -0.2794)
							(mid -0.249642 -0.249642)
							(end -0.2794 -0.1778)
						)
						(arc
							(start -0.2794 0.1778)
							(mid -0.249642 0.249642)
							(end -0.1778 0.2794)
						)
						(arc
							(start 0.1778 0.2794)
							(mid 0.249642 0.249642)
							(end 0.2794 0.1778)
						)
						(arc
							(start 0.2794 -0.1778)
							(mid 0.249642 -0.249642)
							(end 0.1778 -0.2794)
						)
					)
					(width 0)
					(fill yes)
				)
			)
		)
		(pad "2" smd custom
			(at 0 0.4445 270)
			(size 0.1397 0.1397)
			(layers "F.Cu" "F.Mask" "F.Paste")
			(net "I2C_SCC_SCL_R")
			(options
				(clearance outline)
				(anchor circle)
			)
			(primitives
				(gr_poly
					(pts
						(arc
							(start -0.1778 -0.2794)
							(mid -0.249642 -0.249642)
							(end -0.2794 -0.1778)
						)
						(arc
							(start -0.2794 0.1778)
							(mid -0.249642 0.249642)
							(end -0.1778 0.2794)
						)
						(arc
							(start 0.1778 0.2794)
							(mid 0.249642 0.249642)
							(end 0.2794 0.1778)
						)
						(arc
							(start 0.2794 -0.1778)
							(mid 0.249642 -0.249642)
							(end 0.1778 -0.2794)
						)
					)
					(width 0)
					(fill yes)
				)
			)
		)
	)
	(footprint ""
		(layer "F.Cu")
		(at 45.331126 -132.002022 180)
		(property "Reference" "R158"
			(at 0 0 180)
			(layer "F.SilkS")
			(hide yes)
			(effects
				(font
					(size 1.27 1.27)
				)
			)
		)
		(property "Value" "0R2J-2-GP"
			(at 0.064008 -3.993896 180)
			(unlocked yes)
			(layer "F.Fab")
			(hide yes)
			(effects
				(font
					(size 1.016 1.016)
					(thickness 0.1524)
				)
			)
		)
		(property "Device Type" "R402H16"
			(at 0.064008 -5.517896 180)
			(unlocked yes)
			(layer "F.Fab")
			(hide yes)
			(effects
				(font
					(size 1.016 1.016)
					(thickness 0.1524)
				)
			)
		)
		(duplicate_pad_numbers_are_jumpers no)
		(fp_line
			(start 0.508 -0.9398)
			(end -0.508 -0.9398)
			(stroke
				(width 0.1524)
				(type default)
			)
			(layer "F.SilkS")
		)
		(fp_line
			(start -0.508 -0.9398)
			(end -0.508 0.9398)
			(stroke
				(width 0.1524)
				(type default)
			)
			(layer "F.SilkS")
		)
		(fp_rect
			(start -0.508 0.9398)
			(end 0.508 -0.9398)
			(stroke
				(width 0)
				(type default)
			)
			(fill no)
			(layer "F.CrtYd")
		)
		(fp_rect
			(start -0.508 0.9398)
			(end 0.508 -0.9398)
			(stroke
				(width 0)
				(type default)
			)
			(fill no)
			(layer "F.Fab")
		)
		(pad "1" smd custom
			(at 0 -0.4445 180)
			(size 0.1397 0.1397)
			(layers "F.Cu" "F.Mask" "F.Paste")
			(net "BMC_SMB2_DAT_TP")
			(options
				(clearance outline)
				(anchor circle)
			)
			(primitives
				(gr_poly
					(pts
						(arc
							(start -0.1778 -0.2794)
							(mid -0.249642 -0.249642)
							(end -0.2794 -0.1778)
						)
						(arc
							(start -0.2794 0.1778)
							(mid -0.249642 0.249642)
							(end -0.1778 0.2794)
						)
						(arc
							(start 0.1778 0.2794)
							(mid 0.249642 0.249642)
							(end 0.2794 0.1778)
						)
						(arc
							(start 0.2794 -0.1778)
							(mid 0.249642 -0.249642)
							(end 0.1778 -0.2794)
						)
					)
					(width 0)
					(fill yes)
				)
			)
		)
		(pad "2" smd custom
			(at 0 0.4445 180)
			(size 0.1397 0.1397)
			(layers "F.Cu" "F.Mask" "F.Paste")
			(net "BMC_SMB2_DAT")
			(options
				(clearance outline)
				(anchor circle)
			)
			(primitives
				(gr_poly
					(pts
						(arc
							(start -0.1778 -0.2794)
							(mid -0.249642 -0.249642)
							(end -0.2794 -0.1778)
						)
						(arc
							(start -0.2794 0.1778)
							(mid -0.249642 0.249642)
							(end -0.1778 0.2794)
						)
						(arc
							(start 0.1778 0.2794)
							(mid 0.249642 0.249642)
							(end 0.2794 0.1778)
						)
						(arc
							(start 0.2794 -0.1778)
							(mid 0.249642 -0.249642)
							(end 0.1778 -0.2794)
						)
					)
					(width 0)
					(fill yes)
				)
			)
		)
	)
	(footprint ""
		(layer "F.Cu")
		(at 49.09439 -158.5976)
		(property "Reference" "R168"
			(at 0 0 0)
			(layer "F.SilkS")
			(hide yes)
			(effects
				(font
					(size 1.27 1.27)
				)
			)
		)
		(property "Value" "0R2J-2-GP"
			(at 0.064008 -3.993896 0)
			(unlocked yes)
			(layer "F.Fab")
			(hide yes)
			(effects
				(font
					(size 1.016 1.016)
					(thickness 0.1524)
				)
			)
		)
		(property "Device Type" "R402H16"
			(at 0.064008 -5.517896 0)
			(unlocked yes)
			(layer "F.Fab")
			(hide yes)
			(effects
				(font
					(size 1.016 1.016)
					(thickness 0.1524)
				)
			)
		)
		(duplicate_pad_numbers_are_jumpers no)
		(fp_line
			(start -0.508 -0.9398)
			(end -0.508 0.9398)
			(stroke
				(width 0.1524)
				(type default)
			)
			(layer "F.SilkS")
		)
		(fp_line
			(start 0.508 -0.9398)
			(end -0.508 -0.9398)
			(stroke
				(width 0.1524)
				(type default)
			)
			(layer "F.SilkS")
		)
		(fp_rect
			(start -0.508 0.9398)
			(end 0.508 -0.9398)
			(stroke
				(width 0)
				(type default)
			)
			(fill no)
			(layer "F.CrtYd")
		)
		(fp_rect
			(start -0.508 0.9398)
			(end 0.508 -0.9398)
			(stroke
				(width 0)
				(type default)
			)
			(fill no)
			(layer "F.Fab")
		)
		(pad "1" smd custom
			(at 0 -0.4445)
			(size 0.1397 0.1397)
			(layers "F.Cu" "F.Mask" "F.Paste")
			(net "I2C_DPB_MISC_SCL_OUT")
			(options
				(clearance outline)
				(anchor circle)
			)
			(primitives
				(gr_poly
					(pts
						(arc
							(start -0.1778 -0.2794)
							(mid -0.249642 -0.249642)
							(end -0.2794 -0.1778)
						)
						(arc
							(start -0.2794 0.1778)
							(mid -0.249642 0.249642)
							(end -0.1778 0.2794)
						)
						(arc
							(start 0.1778 0.2794)
							(mid 0.249642 0.249642)
							(end 0.2794 0.1778)
						)
						(arc
							(start 0.2794 -0.1778)
							(mid 0.249642 -0.249642)
							(end 0.1778 -0.2794)
						)
					)
					(width 0)
					(fill yes)
				)
			)
		)
		(pad "2" smd custom
			(at 0 0.4445)
			(size 0.1397 0.1397)
			(layers "F.Cu" "F.Mask" "F.Paste")
			(net "BMC_SMB6_CLK")
			(options
				(clearance outline)
				(anchor circle)
			)
			(primitives
				(gr_poly
					(pts
						(arc
							(start -0.1778 -0.2794)
							(mid -0.249642 -0.249642)
							(end -0.2794 -0.1778)
						)
						(arc
							(start -0.2794 0.1778)
							(mid -0.249642 0.249642)
							(end -0.1778 0.2794)
						)
						(arc
							(start 0.1778 0.2794)
							(mid 0.249642 0.249642)
							(end 0.2794 0.1778)
						)
						(arc
							(start 0.2794 -0.1778)
							(mid 0.249642 -0.249642)
							(end 0.1778 -0.2794)
						)
					)
					(width 0)
					(fill yes)
				)
			)
		)
	)
	(footprint ""
		(layer "F.Cu")
		(at 88.768428 -49.168812 90)
		(property "Reference" "R523"
			(at 0 0 90)
			(layer "F.SilkS")
			(hide yes)
			(effects
				(font
					(size 1.27 1.27)
				)
			)
		)
		(property "Value" "1KR2F-3-GP"
			(at 0.064008 -3.993896 90)
			(unlocked yes)
			(layer "F.Fab")
			(hide yes)
			(effects
				(font
					(size 1.016 1.016)
					(thickness 0.1524)
				)
			)
		)
		(property "Device Type" "R402H16"
			(at 0.064008 -5.517896 90)
			(unlocked yes)
			(layer "F.Fab")
			(hide yes)
			(effects
				(font
					(size 1.016 1.016)
					(thickness 0.1524)
				)
			)
		)
		(duplicate_pad_numbers_are_jumpers no)
		(fp_line
			(start 0.508 -0.9398)
			(end -0.508 -0.9398)
			(stroke
				(width 0.1524)
				(type default)
			)
			(layer "F.SilkS")
		)
		(fp_line
			(start -0.508 -0.9398)
			(end -0.508 0.9398)
			(stroke
				(width 0.1524)
				(type default)
			)
			(layer "F.SilkS")
		)
		(fp_rect
			(start -0.508 0.9398)
			(end 0.508 -0.9398)
			(stroke
				(width 0)
				(type default)
			)
			(fill no)
			(layer "F.CrtYd")
		)
		(fp_rect
			(start -0.508 0.9398)
			(end 0.508 -0.9398)
			(stroke
				(width 0)
				(type default)
			)
			(fill no)
			(layer "F.Fab")
		)
		(pad "1" smd custom
			(at 0 -0.4445 90)
			(size 0.1397 0.1397)
			(layers "F.Cu" "F.Mask" "F.Paste")
			(net "P3V3")
			(options
				(clearance outline)
				(anchor circle)
			)
			(primitives
				(gr_poly
					(pts
						(arc
							(start -0.1778 -0.2794)
							(mid -0.249642 -0.249642)
							(end -0.2794 -0.1778)
						)
						(arc
							(start -0.2794 0.1778)
							(mid -0.249642 0.249642)
							(end -0.1778 0.2794)
						)
						(arc
							(start 0.1778 0.2794)
							(mid 0.249642 0.249642)
							(end 0.2794 0.1778)
						)
						(arc
							(start 0.2794 -0.1778)
							(mid 0.249642 -0.249642)
							(end 0.1778 -0.2794)
						)
					)
					(width 0)
					(fill yes)
				)
			)
		)
		(pad "2" smd custom
			(at 0 0.4445 90)
			(size 0.1397 0.1397)
			(layers "F.Cu" "F.Mask" "F.Paste")
			(net "GND")
			(options
				(clearance outline)
				(anchor circle)
			)
			(primitives
				(gr_poly
					(pts
						(arc
							(start -0.1778 -0.2794)
							(mid -0.249642 -0.249642)
							(end -0.2794 -0.1778)
						)
						(arc
							(start -0.2794 0.1778)
							(mid -0.249642 0.249642)
							(end -0.1778 0.2794)
						)
						(arc
							(start 0.1778 0.2794)
							(mid 0.249642 0.249642)
							(end 0.2794 0.1778)
						)
						(arc
							(start 0.2794 -0.1778)
							(mid 0.249642 -0.249642)
							(end 0.1778 -0.2794)
						)
					)
					(width 0)
					(fill yes)
				)
			)
		)
	)
	(footprint ""
		(layer "F.Cu")
		(at 27.419046 -158.588456 -90)
		(property "Reference" "R773"
			(at 0 0 270)
			(layer "F.SilkS")
			(hide yes)
			(effects
				(font
					(size 1.27 1.27)
				)
			)
		)
		(property "Value" "0R2J-2-GP"
			(at 0.064008 -3.993896 270)
			(unlocked yes)
			(layer "F.Fab")
			(hide yes)
			(effects
				(font
					(size 1.016 1.016)
					(thickness 0.1524)
				)
			)
		)
		(property "Device Type" "R402H16"
			(at 0.064008 -5.517896 270)
			(unlocked yes)
			(layer "F.Fab")
			(hide yes)
			(effects
				(font
					(size 1.016 1.016)
					(thickness 0.1524)
				)
			)
		)
		(duplicate_pad_numbers_are_jumpers no)
		(fp_line
			(start -0.508 -0.9398)
			(end -0.508 0.9398)
			(stroke
				(width 0.1524)
				(type default)
			)
			(layer "F.SilkS")
		)
		(fp_line
			(start 0.508 -0.9398)
			(end -0.508 -0.9398)
			(stroke
				(width 0.1524)
				(type default)
			)
			(layer "F.SilkS")
		)
		(fp_rect
			(start -0.508 0.9398)
			(end 0.508 -0.9398)
			(stroke
				(width 0)
				(type default)
			)
			(fill no)
			(layer "F.CrtYd")
		)
		(fp_rect
			(start -0.508 0.9398)
			(end 0.508 -0.9398)
			(stroke
				(width 0)
				(type default)
			)
			(fill no)
			(layer "F.Fab")
		)
		(pad "1" smd custom
			(at 0 -0.4445 270)
			(size 0.1397 0.1397)
			(layers "F.Cu" "F.Mask" "F.Paste")
			(net "DEBUG_GPIO_BMC_R_6")
			(options
				(clearance outline)
				(anchor circle)
			)
			(primitives
				(gr_poly
					(pts
						(arc
							(start -0.1778 -0.2794)
							(mid -0.249642 -0.249642)
							(end -0.2794 -0.1778)
						)
						(arc
							(start -0.2794 0.1778)
							(mid -0.249642 0.249642)
							(end -0.1778 0.2794)
						)
						(arc
							(start 0.1778 0.2794)
							(mid 0.249642 0.249642)
							(end 0.2794 0.1778)
						)
						(arc
							(start 0.2794 -0.1778)
							(mid 0.249642 -0.249642)
							(end 0.1778 -0.2794)
						)
					)
					(width 0)
					(fill yes)
				)
			)
		)
		(pad "2" smd custom
			(at 0 0.4445 270)
			(size 0.1397 0.1397)
			(layers "F.Cu" "F.Mask" "F.Paste")
			(net "DEBUG_GPIO_BMC_6")
			(options
				(clearance outline)
				(anchor circle)
			)
			(primitives
				(gr_poly
					(pts
						(arc
							(start -0.1778 -0.2794)
							(mid -0.249642 -0.249642)
							(end -0.2794 -0.1778)
						)
						(arc
							(start -0.2794 0.1778)
							(mid -0.249642 0.249642)
							(end -0.1778 0.2794)
						)
						(arc
							(start 0.1778 0.2794)
							(mid 0.249642 0.249642)
							(end 0.2794 0.1778)
						)
						(arc
							(start 0.2794 -0.1778)
							(mid 0.249642 -0.249642)
							(end 0.1778 -0.2794)
						)
					)
					(width 0)
					(fill yes)
				)
			)
		)
	)
	(footprint ""
		(layer "F.Cu")
		(at 30.3784 -159.2834 180)
		(property "Reference" "R368"
			(at 0 0 180)
			(layer "F.SilkS")
			(hide yes)
			(effects
				(font
					(size 1.27 1.27)
				)
			)
		)
		(property "Value" "0R2J-2-GP"
			(at 0.064008 -3.993896 180)
			(unlocked yes)
			(layer "F.Fab")
			(hide yes)
			(effects
				(font
					(size 1.016 1.016)
					(thickness 0.1524)
				)
			)
		)
		(property "Device Type" "R402H16"
			(at 0.064008 -5.517896 180)
			(unlocked yes)
			(layer "F.Fab")
			(hide yes)
			(effects
				(font
					(size 1.016 1.016)
					(thickness 0.1524)
				)
			)
		)
		(duplicate_pad_numbers_are_jumpers no)
		(fp_line
			(start 0.508 -0.9398)
			(end -0.508 -0.9398)
			(stroke
				(width 0.1524)
				(type default)
			)
			(layer "F.SilkS")
		)
		(fp_line
			(start -0.508 -0.9398)
			(end -0.508 0.9398)
			(stroke
				(width 0.1524)
				(type default)
			)
			(layer "F.SilkS")
		)
		(fp_rect
			(start -0.508 0.9398)
			(end 0.508 -0.9398)
			(stroke
				(width 0)
				(type default)
			)
			(fill no)
			(layer "F.CrtYd")
		)
		(fp_rect
			(start -0.508 0.9398)
			(end 0.508 -0.9398)
			(stroke
				(width 0)
				(type default)
			)
			(fill no)
			(layer "F.Fab")
		)
		(pad "1" smd custom
			(at 0 -0.4445 180)
			(size 0.1397 0.1397)
			(layers "F.Cu" "F.Mask" "F.Paste")
			(net "P3V3_STBY")
			(options
				(clearance outline)
				(anchor circle)
			)
			(primitives
				(gr_poly
					(pts
						(arc
							(start -0.1778 -0.2794)
							(mid -0.249642 -0.249642)
							(end -0.2794 -0.1778)
						)
						(arc
							(start -0.2794 0.1778)
							(mid -0.249642 0.249642)
							(end -0.1778 0.2794)
						)
						(arc
							(start 0.1778 0.2794)
							(mid 0.249642 0.249642)
							(end 0.2794 0.1778)
						)
						(arc
							(start 0.2794 -0.1778)
							(mid 0.249642 -0.249642)
							(end 0.1778 -0.2794)
						)
					)
					(width 0)
					(fill yes)
				)
			)
		)
		(pad "2" smd custom
			(at 0 0.4445 180)
			(size 0.1397 0.1397)
			(layers "F.Cu" "F.Mask" "F.Paste")
			(net "DACAV33")
			(options
				(clearance outline)
				(anchor circle)
			)
			(primitives
				(gr_poly
					(pts
						(arc
							(start -0.1778 -0.2794)
							(mid -0.249642 -0.249642)
							(end -0.2794 -0.1778)
						)
						(arc
							(start -0.2794 0.1778)
							(mid -0.249642 0.249642)
							(end -0.1778 0.2794)
						)
						(arc
							(start 0.1778 0.2794)
							(mid 0.249642 0.249642)
							(end 0.2794 0.1778)
						)
						(arc
							(start 0.2794 -0.1778)
							(mid 0.249642 -0.249642)
							(end 0.1778 -0.2794)
						)
					)
					(width 0)
					(fill yes)
				)
			)
		)
	)
)
